# S9S_MB_2U (Grand Teton) — schematic netlist excerpt (pin names and nets, part order shuffled) for the footprints in the layout excerpt that follows; sources: Cadence DE-HDL packaged netlist, KiCad conversion of 03242023_DA0F0TMBIJ0_F0T_Motherboard_J_brd_V01_OCP.brd

R1854  Q_RES  10K 1% CHIP  pkg 0402LF  page 242 : A = P3V3_AUX ; B = FM_SCM_PRSNT1_N
PC301  Q_CAP  100NF 50V 10% X7R  pkg C0402  page 267 : A = SW_PVCCIN_CPU0_BOOT1_R ; B = SW_PVCCIN_CPU0_BOOTR1

(kicad_pcb
	(version 20260206)
	(generator "pcbnew")
	(generator_version "10.0")
	(general
		(thickness 1.6)
		(legacy_teardrops no)
	)
	(paper "A4")
	(title_block
		(title "03242023_DA0F0TMBIJ0_F0T_Motherboard_J_brd_V01_OCP.brd")
		(comment 1 "Grand Teton / footprints 1785-1786 of 6105")
	)
	(layers
		(0 "F.Cu" signal "TOP")
		(4 "In1.Cu" signal "GND")
		(6 "In2.Cu" signal "IN1")
		(8 "In3.Cu" signal "GND1")
		(10 "In4.Cu" signal "IN2")
		(12 "In5.Cu" signal "GND2")
		(14 "In6.Cu" signal "IN3")
		(16 "In7.Cu" signal "GND3")
		(18 "In8.Cu" signal "VCC")
		(20 "In9.Cu" signal "VCC1")
		(22 "In10.Cu" signal "GND4")
		(24 "In11.Cu" signal "IN4")
		(26 "In12.Cu" signal "GND5")
		(28 "In13.Cu" signal "IN5")
		(30 "In14.Cu" signal "GND6")
		(32 "In15.Cu" signal "IN6")
		(34 "In16.Cu" signal "GND7")
		(2 "B.Cu" signal "BOTTOM")
		(9 "F.Adhes" user "F.Adhesive")
		(11 "B.Adhes" user "B.Adhesive")
		(13 "F.Paste" user "Package Geometry/Pastemask Top")
		(15 "B.Paste" user "Package Geometry/Pastemask Bottom")
		(5 "F.SilkS" user "Ref Des/Silkscreen Top")
		(7 "B.SilkS" user "Ref Des/Silkscreen Bottom")
		(1 "F.Mask" user "Board Geometry/Soldermask Top")
		(3 "B.Mask" user "Board Geometry/Soldermask Bottom")
		(17 "Dwgs.User" user "User.Drawings")
		(19 "Cmts.User" user "User.Comments")
		(21 "Eco1.User" user "User.Eco1")
		(23 "Eco2.User" user "User.Eco2")
		(25 "Edge.Cuts" user "Board Geometry/Outline")
		(27 "Margin" user)
		(31 "F.CrtYd" user "Package Geometry/Place Bound Top")
		(29 "B.CrtYd" user "Package Geometry/Place Bound Bottom")
		(35 "F.Fab" user "Ref Des/Assembly Top")
		(33 "B.Fab" user "Ref Des/Assembly Bottom")
	)
	(footprint ""
		(layer "F.Cu")
		(at 347.00718 -338.180172 -90)
		(property "Reference" "PC301"
			(at 0 0 270)
			(layer "F.SilkS")
			(hide yes)
			(effects
				(font
					(size 1.27 1.27)
				)
			)
		)
		(property "Value" ""
			(at 0 0 270)
			(layer "F.Fab")
			(effects
				(font
					(size 1.27 1.27)
				)
			)
		)
		(duplicate_pad_numbers_are_jumpers no)
		(fp_line
			(start -0.7874 0.4064)
			(end -0.7874 -0.4064)
			(stroke
				(width 0.1524)
				(type default)
			)
			(layer "F.SilkS")
		)
		(fp_line
			(start 0.7874 0.4064)
			(end -0.7874 0.4064)
			(stroke
				(width 0.1524)
				(type default)
			)
			(layer "F.SilkS")
		)
		(fp_line
			(start -0.7874 -0.4064)
			(end 0.7874 -0.4064)
			(stroke
				(width 0.1524)
				(type default)
			)
			(layer "F.SilkS")
		)
		(fp_line
			(start 0.7874 -0.4064)
			(end 0.7874 0.4064)
			(stroke
				(width 0.1524)
				(type default)
			)
			(layer "F.SilkS")
		)
		(fp_line
			(start -0.67945 0.3048)
			(end -0.67945 -0.305054)
			(stroke
				(width 0.1)
				(type default)
			)
			(layer "F.Fab")
		)
		(fp_line
			(start -0.12065 0.3048)
			(end -0.67945 0.3048)
			(stroke
				(width 0.1)
				(type default)
			)
			(layer "F.Fab")
		)
		(fp_line
			(start 0.120396 0.3048)
			(end 0.120396 0.2794)
			(stroke
				(width 0.1)
				(type default)
			)
			(layer "F.Fab")
		)
		(fp_line
			(start 0.67945 0.3048)
			(end 0.120396 0.3048)
			(stroke
				(width 0.1)
				(type default)
			)
			(layer "F.Fab")
		)
		(fp_line
			(start -0.12065 0.2794)
			(end -0.12065 0.3048)
			(stroke
				(width 0.1)
				(type default)
			)
			(layer "F.Fab")
		)
		(fp_line
			(start 0.120396 0.2794)
			(end -0.12065 0.2794)
			(stroke
				(width 0.1)
				(type default)
			)
			(layer "F.Fab")
		)
		(fp_line
			(start -0.12065 -0.2794)
			(end 0.12065 -0.2794)
			(stroke
				(width 0.1)
				(type default)
			)
			(layer "F.Fab")
		)
		(fp_line
			(start 0.12065 -0.2794)
			(end 0.12065 -0.3048)
			(stroke
				(width 0.1)
				(type default)
			)
			(layer "F.Fab")
		)
		(fp_line
			(start 0.12065 -0.3048)
			(end 0.67945 -0.3048)
			(stroke
				(width 0.1)
				(type default)
			)
			(layer "F.Fab")
		)
		(fp_line
			(start 0.67945 -0.3048)
			(end 0.67945 0.3048)
			(stroke
				(width 0.1)
				(type default)
			)
			(layer "F.Fab")
		)
		(fp_line
			(start -0.67945 -0.305054)
			(end -0.12065 -0.305054)
			(stroke
				(width 0.1)
				(type default)
			)
			(layer "F.Fab")
		)
		(fp_line
			(start -0.12065 -0.305054)
			(end -0.12065 -0.2794)
			(stroke
				(width 0.1)
				(type default)
			)
			(layer "F.Fab")
		)
		(pad "1" smd circle
			(at -0.40005 0 270)
			(size 0 0)
			(layers "F.Cu" "F.Mask" "F.Paste")
			(net "SW_PVCCIN_CPU0_BOOT1_R")
		)
		(pad "2" smd circle
			(at 0.40005 0 270)
			(size 0 0)
			(layers "F.Cu" "F.Mask" "F.Paste")
			(net "SW_PVCCIN_CPU0_BOOTR1")
		)
	)
	(footprint ""
		(layer "F.Cu")
		(at 189.80023 -35.017456 180)
		(property "Reference" "R1854"
			(at 0 0 180)
			(layer "F.SilkS")
			(hide yes)
			(effects
				(font
					(size 1.27 1.27)
				)
			)
		)
		(property "Value" ""
			(at 0 0 180)
			(layer "F.Fab")
			(effects
				(font
					(size 1.27 1.27)
				)
			)
		)
		(duplicate_pad_numbers_are_jumpers no)
		(fp_line
			(start 0.7874 0.4064)
			(end -0.7874 0.4064)
			(stroke
				(width 0.1524)
				(type default)
			)
			(layer "F.SilkS")
		)
		(fp_line
			(start 0.7874 -0.4064)
			(end 0.7874 0.4064)
			(stroke
				(width 0.1524)
				(type default)
			)
			(layer "F.SilkS")
		)
		(fp_line
			(start -0.7874 0.4064)
			(end -0.7874 -0.4064)
			(stroke
				(width 0.1524)
				(type default)
			)
			(layer "F.SilkS")
		)
		(fp_line
			(start -0.7874 -0.4064)
			(end 0.7874 -0.4064)
			(stroke
				(width 0.1524)
				(type default)
			)
			(layer "F.SilkS")
		)
		(fp_line
			(start 0.67945 0.3048)
			(end 0.120396 0.3048)
			(stroke
				(width 0.1)
				(type default)
			)
			(layer "F.Fab")
		)
		(fp_line
			(start 0.67945 -0.3048)
			(end 0.67945 0.3048)
			(stroke
				(width 0.1)
				(type default)
			)
			(layer "F.Fab")
		)
		(fp_line
			(start 0.12065 -0.2794)
			(end 0.12065 -0.3048)
			(stroke
				(width 0.1)
				(type default)
			)
			(layer "F.Fab")
		)
		(fp_line
			(start 0.12065 -0.3048)
			(end 0.67945 -0.3048)
			(stroke
				(width 0.1)
				(type default)
			)
			(layer "F.Fab")
		)
		(fp_line
			(start 0.120396 0.3048)
			(end 0.120396 0.2794)
			(stroke
				(width 0.1)
				(type default)
			)
			(layer "F.Fab")
		)
		(fp_line
			(start 0.120396 0.2794)
			(end -0.12065 0.2794)
			(stroke
				(width 0.1)
				(type default)
			)
			(layer "F.Fab")
		)
		(fp_line
			(start -0.12065 0.3048)
			(end -0.67945 0.3048)
			(stroke
				(width 0.1)
				(type default)
			)
			(layer "F.Fab")
		)
		(fp_line
			(start -0.12065 0.2794)
			(end -0.12065 0.3048)
			(stroke
				(width 0.1)
				(type default)
			)
			(layer "F.Fab")
		)
		(fp_line
			(start -0.12065 -0.2794)
			(end 0.12065 -0.2794)
			(stroke
				(width 0.1)
				(type default)
			)
			(layer "F.Fab")
		)
		(fp_line
			(start -0.12065 -0.305054)
			(end -0.12065 -0.2794)
			(stroke
				(width 0.1)
				(type default)
			)
			(layer "F.Fab")
		)
		(fp_line
			(start -0.67945 0.3048)
			(end -0.67945 -0.305054)
			(stroke
				(width 0.1)
				(type default)
			)
			(layer "F.Fab")
		)
		(fp_line
			(start -0.67945 -0.305054)
			(end -0.12065 -0.305054)
			(stroke
				(width 0.1)
				(type default)
			)
			(layer "F.Fab")
		)
		(pad "1" smd circle
			(at -0.40005 0 180)
			(size 0 0)
			(layers "F.Cu" "F.Mask" "F.Paste")
			(net "P3V3_AUX")
		)
		(pad "2" smd circle
			(at 0.40005 0 180)
			(size 0 0)
			(layers "F.Cu" "F.Mask" "F.Paste")
			(net "FM_SCM_PRSNT1_N")
		)
	)
)
